# S9S_MB_2U (Grand Teton) — schematic netlist excerpt (pin names and nets, part order shuffled) for the footprints in the layout excerpt that follows; sources: Cadence DE-HDL packaged netlist, KiCad conversion of 03242023_DA0F0TMBIJ0_F0T_Motherboard_J_brd_V01_OCP.brd

J112  CONN160_10131762101LF  CONN160_10131762-101LF IO  pkg HSD_F160D8_P2W1-2_RDH  page 143
  A1  = RST_PERST_2_SWB_BUF_N
  A2  = GND
  A3  = HGX_DETECT_N_ISO
  A4  = GND
  A5  = RST_PERST_1_SWB_BUF_N
  A6  = GND
  A7  = PRSNT_SWB_N
  A8  = GND
  B1  = GND
  B2  = P5E_CPU1_PE0_RX_DN<14>
  B3  = GND
  B4  = P5E_CPU1_PE0_RX_DN<12>
  B5  = GND
  B6  = P5E_CPU1_PE0_RX_DN<10>
  B7  = GND
  B8  = P5E_CPU1_PE0_RX_DN<8>
  C1  = P5E_CPU1_PE0_RX_DN<15>
  C2  = P5E_CPU1_PE0_RX_DP<14>
  C3  = P5E_CPU1_PE0_RX_DN<13>
  C4  = P5E_CPU1_PE0_RX_DP<12>
  C5  = P5E_CPU1_PE0_RX_DP<11>
  C6  = P5E_CPU1_PE0_RX_DP<10>
  C7  = P5E_CPU1_PE0_RX_DN<9>
  C8  = P5E_CPU1_PE0_RX_DP<8>
  D1  = P5E_CPU1_PE0_RX_DP<15>
  D2  = GND
  D3  = P5E_CPU1_PE0_RX_DP<13>
  D4  = GND
  D5  = P5E_CPU1_PE0_RX_DN<11>
  D6  = GND
  D7  = P5E_CPU1_PE0_RX_DP<9>
  D8  = GND
  E1  = GND
  E2  = P5E_CPU1_PE4_RX_DP<1>
  E3  = GND
  E4  = P5E_CPU1_PE4_RX_DP<3>
  E5  = GND
  E6  = P5E_CPU1_PE4_RX_DP<5>
  E7  = GND
  E8  = P5E_CPU1_PE4_RX_DP<7>
  F1  = P5E_CPU1_PE4_RX_DN<0>
  F2  = P5E_CPU1_PE4_RX_DN<1>
  F3  = P5E_CPU1_PE4_RX_DN<2>
  F4  = P5E_CPU1_PE4_RX_DN<3>
  F5  = P5E_CPU1_PE4_RX_DN<4>
  F6  = P5E_CPU1_PE4_RX_DN<5>
  F7  = P5E_CPU1_PE4_RX_DN<6>
  F8  = P5E_CPU1_PE4_RX_DN<7>
  G1  = P5E_CPU1_PE4_RX_DP<0>
  G2  = GND
  G3  = P5E_CPU1_PE4_RX_DP<2>
  G4  = GND
  G5  = P5E_CPU1_PE4_RX_DP<4>
  G6  = GND
  G7  = P5E_CPU1_PE4_RX_DP<6>
  G8  = GND
  H1  = GND
  H2  = P5E_CPU1_PE0_TX_C_DN<14>
  H3  = GND
  H4  = P5E_CPU1_PE0_TX_C_DN<12>
  H5  = GND
  H6  = P5E_CPU1_PE0_TX_C_DN<10>
  H7  = GND
  H8  = P5E_CPU1_PE0_TX_C_DN<8>
  I1  = P5E_CPU1_PE0_TX_C_DN<15>
  I2  = P5E_CPU1_PE0_TX_C_DP<14>
  I3  = P5E_CPU1_PE0_TX_C_DN<13>
  I4  = P5E_CPU1_PE0_TX_C_DP<12>
  I5  = P5E_CPU1_PE0_TX_C_DN<11>
  I6  = P5E_CPU1_PE0_TX_C_DP<10>
  I7  = P5E_CPU1_PE0_TX_C_DN<9>
  I8  = P5E_CPU1_PE0_TX_C_DP<8>
  J1  = P5E_CPU1_PE0_TX_C_DP<15>
  J2  = GND
  J3  = P5E_CPU1_PE0_TX_C_DP<13>
  J4  = GND
  J5  = P5E_CPU1_PE0_TX_C_DP<11>
  J6  = GND
  J7  = P5E_CPU1_PE0_TX_C_DP<9>
  J8  = GND
  K1  = GND
  K2  = P5E_CPU1_PE4_TX_C_DP<1>
  K3  = GND
  K4  = P5E_CPU1_PE4_TX_C_DN<3>
  K5  = GND
  K6  = P5E_CPU1_PE4_TX_C_DN<5>
  K7  = GND
  K8  = P5E_CPU1_PE4_TX_C_DN<7>
  L1  = P5E_CPU1_PE4_TX_C_DN<0>
  L2  = P5E_CPU1_PE4_TX_C_DN<1>
  L3  = P5E_CPU1_PE4_TX_C_DN<2>
  L4  = P5E_CPU1_PE4_TX_C_DP<3>
  L5  = P5E_CPU1_PE4_TX_C_DN<4>
  L6  = P5E_CPU1_PE4_TX_C_DP<5>
  L7  = P5E_CPU1_PE4_TX_C_DN<6>
  L8  = P5E_CPU1_PE4_TX_C_DP<7>
  M1  = P5E_CPU1_PE4_TX_C_DP<0>
  M2  = GND
  M3  = P5E_CPU1_PE4_TX_C_DP<2>
  M4  = GND
  M5  = P5E_CPU1_PE4_TX_C_DP<4>
  M6  = GND
  M7  = P5E_CPU1_PE4_TX_C_DP<6>
  M8  = GND
  N1  = GND
  N2  = NC_J112_N2
  N3  = GND
  N4  = CLK_100M_GPU_1_DN
  N5  = GND
  N6  = P2E_MB_BMC_RX_DN<0>
  N7  = GND
  N8  = P3E_PCH_NVS_RX_DN<0>
  O1  = CLK_100M_GPU_2_DN
  O2  = NC_J112_O2
  O3  = CLK_100M_SWB_DN
  O4  = CLK_100M_GPU_1_DP
  O5  = NC_J112_O5
  O6  = P2E_MB_BMC_RX_DP<0>
  O7  = P3E_PCH_NVS_RX_DN<1>
  O8  = P3E_PCH_NVS_RX_DP<0>
  P1  = CLK_100M_GPU_2_DP
  P2  = GND
  P3  = CLK_100M_SWB_DP
  P4  = GND
  P5  = NC_J112_P5
  P6  = GND
  P7  = P3E_PCH_NVS_RX_DP<1>
  P8  = GND
  Q1  = GND
  Q2  = CLK_100M_GPU_FPGA_DN
  Q3  = GND
  Q4  = SMB_1_BMC_GPU_BUF_SCL
  Q5  = GND
  Q6  = P2E_MB_BMC_TX_BUF_C_DN<0>
  Q7  = GND
  Q8  = P3E_PCH_NVS_TX_C_DN<0>
  R1  = USB2_HUB_BUF_SWB_DN
  R2  = CLK_100M_GPU_FPGA_DP
  R3  = SMB_2_BMC_GPU_BUF_SCL
  R4  = SMB_1_BMC_GPU_BUF_SDA
  R5  = NC_J112_R5
  R6  = P2E_MB_BMC_TX_BUF_C_DP<0>
  R7  = P3E_PCH_NVS_TX_C_DN<1>
  R8  = P3E_PCH_NVS_TX_C_DP<0>
  S1  = USB2_HUB_BUF_SWB_DP
  S2  = GND
  S3  = SMB_2_BMC_GPU_BUF_SDA
  S4  = GND
  S5  = NC_J112_S5
  S6  = GND
  S7  = P3E_PCH_NVS_TX_C_DP<1>
  S8  = GND
  T1  = GND
  T2  = GPU_FPGA_READY
  T3  = GND
  T4  = GPU_NVS_PWR_BRAKE_N_BUF
  T5  = GND
  T6  = GPU_FPGA_THERM_OVERT_N
  T7  = GND
  T8  = RST_PERST_0_SWB_BUF_N

(kicad_pcb
	(version 20260206)
	(generator "pcbnew")
	(generator_version "10.0")
	(general
		(thickness 1.6)
		(legacy_teardrops no)
	)
	(paper "A4")
	(title_block
		(title "03242023_DA0F0TMBIJ0_F0T_Motherboard_J_brd_V01_OCP.brd")
		(comment 1 "Grand Teton / footprint 2126 of 6105 (J112), pads 32-62 of 90")
	)
	(layers
		(0 "F.Cu" signal "TOP")
		(4 "In1.Cu" signal "GND")
		(6 "In2.Cu" signal "IN1")
		(8 "In3.Cu" signal "GND1")
		(10 "In4.Cu" signal "IN2")
		(12 "In5.Cu" signal "GND2")
		(14 "In6.Cu" signal "IN3")
		(16 "In7.Cu" signal "GND3")
		(18 "In8.Cu" signal "VCC")
		(20 "In9.Cu" signal "VCC1")
		(22 "In10.Cu" signal "GND4")
		(24 "In11.Cu" signal "IN4")
		(26 "In12.Cu" signal "GND5")
		(28 "In13.Cu" signal "IN5")
		(30 "In14.Cu" signal "GND6")
		(32 "In15.Cu" signal "IN6")
		(34 "In16.Cu" signal "GND7")
		(2 "B.Cu" signal "BOTTOM")
		(9 "F.Adhes" user "F.Adhesive")
		(11 "B.Adhes" user "B.Adhesive")
		(13 "F.Paste" user "Package Geometry/Pastemask Top")
		(15 "B.Paste" user "Package Geometry/Pastemask Bottom")
		(5 "F.SilkS" user "Ref Des/Silkscreen Top")
		(7 "B.SilkS" user "Ref Des/Silkscreen Bottom")
		(1 "F.Mask" user "Board Geometry/Soldermask Top")
		(3 "B.Mask" user "Board Geometry/Soldermask Bottom")
		(17 "Dwgs.User" user "User.Drawings")
		(19 "Cmts.User" user "User.Comments")
		(21 "Eco1.User" user "User.Eco1")
		(23 "Eco2.User" user "User.Eco2")
		(25 "Edge.Cuts" user "Board Geometry/Outline")
		(27 "Margin" user)
		(31 "F.CrtYd" user "Package Geometry/Place Bound Top")
		(29 "B.CrtYd" user "Package Geometry/Place Bound Bottom")
		(35 "F.Fab" user "Ref Des/Assembly Top")
		(33 "B.Fab" user "Ref Des/Assembly Bottom")
	)
	(footprint ""
		(layer "F.Cu")
		(at 58.650124 -440.489848)
		(property "Reference" "J112"
			(at -7.9883 9.742932 0)
			(unlocked yes)
			(layer "F.SilkS")
			(effects
				(font
					(size 0.7874 0.5842)
					(thickness 0.1524)
				)
				(justify left)
			)
		)
		(property "Value" ""
			(at 0 0 0)
			(layer "F.Fab")
			(effects
				(font
					(size 1.27 1.27)
				)
			)
		)
		(duplicate_pad_numbers_are_jumpers no)
		(pad "J8" thru_hole circle
			(at 13.999972 10.999978 180)
			(size 0.906272 0.906272)
			(drill 0.499872)
			(layers "*.Cu" "*.Mask")
			(remove_unused_layers no)
			(net "GND")
			(clearance 0.0508)
			(thermal_gap 0.0508)
		)
		(pad "K1" thru_hole circle
			(at 0 11.999976 180)
			(size 0.906272 0.906272)
			(drill 0.499872)
			(layers "*.Cu" "*.Mask")
			(remove_unused_layers no)
			(net "GND")
			(clearance 0.0508)
			(thermal_gap 0.0508)
		)
		(pad "K3" thru_hole circle
			(at 3.999992 11.999976 180)
			(size 0.906272 0.906272)
			(drill 0.499872)
			(layers "*.Cu" "*.Mask")
			(remove_unused_layers no)
			(net "GND")
			(clearance 0.0508)
			(thermal_gap 0.0508)
		)
		(pad "K5" thru_hole circle
			(at 7.999984 11.999976 180)
			(size 0.906272 0.906272)
			(drill 0.499872)
			(layers "*.Cu" "*.Mask")
			(remove_unused_layers no)
			(net "GND")
			(clearance 0.0508)
			(thermal_gap 0.0508)
		)
		(pad "K7" thru_hole circle
			(at 11.999976 11.999976 180)
			(size 0.906272 0.906272)
			(drill 0.499872)
			(layers "*.Cu" "*.Mask")
			(remove_unused_layers no)
			(net "GND")
			(clearance 0.0508)
			(thermal_gap 0.0508)
		)
		(pad "M2" thru_hole circle
			(at 1.999996 14.59992 180)
			(size 0.906272 0.906272)
			(drill 0.499872)
			(layers "*.Cu" "*.Mask")
			(remove_unused_layers no)
			(net "GND")
			(clearance 0.0508)
			(thermal_gap 0.0508)
		)
		(pad "M4" thru_hole circle
			(at 5.999988 14.59992 180)
			(size 0.906272 0.906272)
			(drill 0.499872)
			(layers "*.Cu" "*.Mask")
			(remove_unused_layers no)
			(net "GND")
			(clearance 0.0508)
			(thermal_gap 0.0508)
		)
		(pad "M6" thru_hole circle
			(at 9.99998 14.59992 180)
			(size 0.906272 0.906272)
			(drill 0.499872)
			(layers "*.Cu" "*.Mask")
			(remove_unused_layers no)
			(net "GND")
			(clearance 0.0508)
			(thermal_gap 0.0508)
		)
		(pad "M8" thru_hole circle
			(at 13.999972 14.59992 180)
			(size 0.906272 0.906272)
			(drill 0.499872)
			(layers "*.Cu" "*.Mask")
			(remove_unused_layers no)
			(net "GND")
			(clearance 0.0508)
			(thermal_gap 0.0508)
		)
		(pad "N1" thru_hole circle
			(at 0 15.599918 180)
			(size 0.906272 0.906272)
			(drill 0.499872)
			(layers "*.Cu" "*.Mask")
			(remove_unused_layers no)
			(net "GND")
			(clearance 0.0508)
			(thermal_gap 0.0508)
		)
		(pad "N2" thru_hole circle
			(at 1.999996 15.80007 180)
			(size 0.766318 0.766318)
			(drill 0.359918)
			(layers "*.Cu" "*.Mask")
			(remove_unused_layers no)
			(net "NC_J112_N2")
			(clearance 0.0508)
			(thermal_gap 0.0508)
		)
		(pad "N3" thru_hole circle
			(at 3.999992 15.599918 180)
			(size 0.906272 0.906272)
			(drill 0.499872)
			(layers "*.Cu" "*.Mask")
			(remove_unused_layers no)
			(net "GND")
			(clearance 0.0508)
			(thermal_gap 0.0508)
		)
		(pad "N4" thru_hole circle
			(at 5.999988 15.80007 180)
			(size 0.766318 0.766318)
			(drill 0.359918)
			(layers "*.Cu" "*.Mask")
			(remove_unused_layers no)
			(net "CLK_100M_GPU_1_DN")
			(clearance 0.0508)
			(thermal_gap 0.0508)
		)
		(pad "N5" thru_hole circle
			(at 7.999984 15.599918 180)
			(size 0.906272 0.906272)
			(drill 0.499872)
			(layers "*.Cu" "*.Mask")
			(remove_unused_layers no)
			(net "GND")
			(clearance 0.0508)
			(thermal_gap 0.0508)
		)
		(pad "N6" thru_hole circle
			(at 9.99998 15.80007 180)
			(size 0.766318 0.766318)
			(drill 0.359918)
			(layers "*.Cu" "*.Mask")
			(remove_unused_layers no)
			(net "P2E_MB_BMC_RX_DN<0>")
			(clearance 0.0508)
			(thermal_gap 0.0508)
		)
		(pad "N7" thru_hole circle
			(at 11.999976 15.599918 180)
			(size 0.906272 0.906272)
			(drill 0.499872)
			(layers "*.Cu" "*.Mask")
			(remove_unused_layers no)
			(net "GND")
			(clearance 0.0508)
			(thermal_gap 0.0508)
		)
		(pad "O1" thru_hole circle
			(at 0 16.800068 180)
			(size 0.766318 0.766318)
			(drill 0.359918)
			(layers "*.Cu" "*.Mask")
			(remove_unused_layers no)
			(net "CLK_100M_GPU_2_DN")
			(clearance 0.0508)
			(thermal_gap 0.0508)
		)
		(pad "O2" thru_hole circle
			(at 1.999996 16.999966 180)
			(size 0.766318 0.766318)
			(drill 0.359918)
			(layers "*.Cu" "*.Mask")
			(remove_unused_layers no)
			(net "NC_J112_O2")
			(clearance 0.0508)
			(thermal_gap 0.0508)
		)
		(pad "O3" thru_hole circle
			(at 3.999992 16.800068 180)
			(size 0.766318 0.766318)
			(drill 0.359918)
			(layers "*.Cu" "*.Mask")
			(remove_unused_layers no)
			(net "CLK_100M_SWB_DN")
			(clearance 0.0508)
			(thermal_gap 0.0508)
		)
		(pad "O4" thru_hole circle
			(at 5.999988 16.999966 180)
			(size 0.766318 0.766318)
			(drill 0.359918)
			(layers "*.Cu" "*.Mask")
			(remove_unused_layers no)
			(net "CLK_100M_GPU_1_DP")
			(clearance 0.0508)
			(thermal_gap 0.0508)
		)
		(pad "O5" thru_hole circle
			(at 7.999984 16.800068 180)
			(size 0.766318 0.766318)
			(drill 0.359918)
			(layers "*.Cu" "*.Mask")
			(remove_unused_layers no)
			(net "NC_J112_O5")
			(clearance 0.0508)
			(thermal_gap 0.0508)
		)
		(pad "O6" thru_hole circle
			(at 9.99998 16.999966 180)
			(size 0.766318 0.766318)
			(drill 0.359918)
			(layers "*.Cu" "*.Mask")
			(remove_unused_layers no)
			(net "P2E_MB_BMC_RX_DP<0>")
			(clearance 0.0508)
			(thermal_gap 0.0508)
		)
		(pad "O7" thru_hole circle
			(at 11.999976 16.800068 180)
			(size 0.766318 0.766318)
			(drill 0.359918)
			(layers "*.Cu" "*.Mask")
			(remove_unused_layers no)
			(net "P3E_PCH_NVS_RX_DN<1>")
			(clearance 0.0508)
			(thermal_gap 0.0508)
		)
		(pad "P1" thru_hole circle
			(at 0 17.999964 180)
			(size 0.766318 0.766318)
			(drill 0.359918)
			(layers "*.Cu" "*.Mask")
			(remove_unused_layers no)
			(net "CLK_100M_GPU_2_DP")
			(clearance 0.0508)
			(thermal_gap 0.0508)
		)
		(pad "P2" thru_hole circle
			(at 1.999996 18.200116 180)
			(size 0.906272 0.906272)
			(drill 0.499872)
			(layers "*.Cu" "*.Mask")
			(remove_unused_layers no)
			(net "GND")
			(clearance 0.0508)
			(thermal_gap 0.0508)
		)
		(pad "P3" thru_hole circle
			(at 3.999992 17.999964 180)
			(size 0.766318 0.766318)
			(drill 0.359918)
			(layers "*.Cu" "*.Mask")
			(remove_unused_layers no)
			(net "CLK_100M_SWB_DP")
			(clearance 0.0508)
			(thermal_gap 0.0508)
		)
		(pad "P4" thru_hole circle
			(at 5.999988 18.200116 180)
			(size 0.906272 0.906272)
			(drill 0.499872)
			(layers "*.Cu" "*.Mask")
			(remove_unused_layers no)
			(net "GND")
			(clearance 0.0508)
			(thermal_gap 0.0508)
		)
		(pad "P5" thru_hole circle
			(at 7.999984 17.999964 180)
			(size 0.766318 0.766318)
			(drill 0.359918)
			(layers "*.Cu" "*.Mask")
			(remove_unused_layers no)
			(net "NC_J112_P5")
			(clearance 0.0508)
			(thermal_gap 0.0508)
		)
		(pad "P6" thru_hole circle
			(at 9.99998 18.200116 180)
			(size 0.906272 0.906272)
			(drill 0.499872)
			(layers "*.Cu" "*.Mask")
			(remove_unused_layers no)
			(net "GND")
			(clearance 0.0508)
			(thermal_gap 0.0508)
		)
		(pad "P7" thru_hole circle
			(at 11.999976 17.999964 180)
			(size 0.766318 0.766318)
			(drill 0.359918)
			(layers "*.Cu" "*.Mask")
			(remove_unused_layers no)
			(net "P3E_PCH_NVS_RX_DP<1>")
			(clearance 0.0508)
			(thermal_gap 0.0508)
		)
		(pad "P8" thru_hole circle
			(at 13.999972 18.200116 180)
			(size 0.906272 0.906272)
			(drill 0.499872)
			(layers "*.Cu" "*.Mask")
			(remove_unused_layers no)
			(net "GND")
			(clearance 0.0508)
			(thermal_gap 0.0508)
		)
	)
)
